# BASEBOARD_FAB2 (Tioga Pass) — schematic netlist excerpt (pin names and nets, part order shuffled) for the footprints in the layout excerpt that follows; sources: Cadence DE-HDL packaged netlist, KiCad conversion of Wiwynn_Tioga_Pass_MB.brd

R8B11  RES  1.8K 1% CHIP  pkg 0402  page 91 : A = PVPP_ABC ; B = SMB_HFI1_CPU0_LVC2_SCL
R1D4  RES  10.0 1% CHIP  pkg 0402  page 206 : A = VSENSE_PVCCIN_CPU1_P ; B = VSENSE_PVCCIN_CPU1_AVSP
U2P1  TTL1G07_A  74LVC1G07 IC  pkg SOP  page 185 : A = FM_M2_SSD_PEDET ; Y = FM_M2_DET_LVC3

(kicad_pcb
	(version 20260206)
	(generator "pcbnew")
	(generator_version "10.0")
	(general
		(thickness 1.6)
		(legacy_teardrops no)
	)
	(paper "A4")
	(title_block
		(title "Wiwynn_Tioga_Pass_MB.brd")
		(comment 1 "Tioga Pass / footprints 1273-1275 of 4770")
	)
	(layers
		(0 "F.Cu" signal "TOP")
		(4 "In1.Cu" signal "L2GND")
		(6 "In2.Cu" signal "L3")
		(8 "In3.Cu" signal "L4GND")
		(10 "In4.Cu" signal "L5")
		(12 "In5.Cu" signal "L6GND")
		(14 "In6.Cu" signal "L7VCC")
		(16 "In7.Cu" signal "L8VCC")
		(18 "In8.Cu" signal "L9GND")
		(20 "In9.Cu" signal "L10")
		(22 "In10.Cu" signal "L11GND")
		(24 "In11.Cu" signal "L12")
		(26 "In12.Cu" signal "L13GND")
		(2 "B.Cu" signal "BOTTOM")
		(9 "F.Adhes" user "F.Adhesive")
		(11 "B.Adhes" user "B.Adhesive")
		(13 "F.Paste" user "Package Geometry/Pastemask Top")
		(15 "B.Paste" user "Package Geometry/Pastemask Bottom")
		(5 "F.SilkS" user "Ref Des/Silkscreen Top")
		(7 "B.SilkS" user "Ref Des/Silkscreen Bottom")
		(1 "F.Mask" user "Board Geometry/Soldermask Top")
		(3 "B.Mask" user "Board Geometry/Soldermask Bottom")
		(17 "Dwgs.User" user "User.Drawings")
		(19 "Cmts.User" user "User.Comments")
		(21 "Eco1.User" user "User.Eco1")
		(23 "Eco2.User" user "User.Eco2")
		(25 "Edge.Cuts" user "Board Geometry/Outline")
		(27 "Margin" user)
		(31 "F.CrtYd" user "Package Geometry/Place Bound Top")
		(29 "B.CrtYd" user "Package Geometry/Place Bound Bottom")
		(35 "F.Fab" user "Ref Des/Assembly Top")
		(33 "B.Fab" user "Ref Des/Assembly Bottom")
	)
	(footprint ""
		(layer "F.Cu")
		(at 21.6408 -87.3506 -90)
		(property "Reference" "R1D4"
			(at 0 0 270)
			(layer "F.SilkS")
			(hide yes)
			(effects
				(font
					(size 1.27 1.27)
				)
			)
		)
		(property "Value" ""
			(at 0 0 270)
			(layer "F.Fab")
			(effects
				(font
					(size 1.27 1.27)
				)
			)
		)
		(duplicate_pad_numbers_are_jumpers no)
		(fp_rect
			(start 0.2794 0.9906)
			(end -0.2794 -0.1016)
			(stroke
				(width 0)
				(type default)
			)
			(fill no)
			(layer "F.CrtYd")
		)
		(fp_line
			(start -0.2794 0.9906)
			(end 0.2794 0.9906)
			(stroke
				(width 0.1)
				(type default)
			)
			(layer "F.Fab")
		)
		(fp_line
			(start 0.2794 0.9906)
			(end 0.2794 -0.1016)
			(stroke
				(width 0.1)
				(type default)
			)
			(layer "F.Fab")
		)
		(fp_line
			(start -0.2794 -0.1016)
			(end -0.2794 0.9906)
			(stroke
				(width 0.1)
				(type default)
			)
			(layer "F.Fab")
		)
		(fp_line
			(start 0.2794 -0.1016)
			(end -0.2794 -0.1016)
			(stroke
				(width 0.1)
				(type default)
			)
			(layer "F.Fab")
		)
		(pad "1" smd rect
			(at 0 0 270)
			(size 0.508 0.508)
			(layers "F.Cu" "F.Mask" "F.Paste")
			(net "VSENSE_PVCCIN_CPU1_P")
		)
		(pad "2" smd rect
			(at 0 0.889 270)
			(size 0.508 0.508)
			(layers "F.Cu" "F.Mask" "F.Paste")
			(net "VSENSE_PVCCIN_CPU1_AVSP")
		)
		(zone
			(layer "F.Cu")
			(hatch none 0.5)
			(connect_pads
				(clearance 0)
			)
			(min_thickness 0.25)
			(keepout
				(tracks not_allowed)
				(vias allowed)
				(pads allowed)
				(copperpour not_allowed)
				(footprints allowed)
			)
			(placement
				(enabled no)
				(sheetname "")
			)
			(fill
				(thermal_gap 0.5)
				(thermal_bridge_width 0.5)
				(island_removal_mode 0)
			)
			(polygon
				(pts
					(xy 21.0058 -87.0966) (xy 21.3868 -87.0966) (xy 21.3868 -87.6046) (xy 21.0058 -87.6046)
				)
			)
		)
		(zone
			(layer "F.Cu")
			(hatch none 0.5)
			(connect_pads
				(clearance 0)
			)
			(min_thickness 0.25)
			(keepout
				(tracks allowed)
				(vias not_allowed)
				(pads allowed)
				(copperpour not_allowed)
				(footprints allowed)
			)
			(placement
				(enabled no)
				(sheetname "")
			)
			(fill
				(thermal_gap 0.5)
				(thermal_bridge_width 0.5)
				(island_removal_mode 0)
			)
			(polygon
				(pts
					(xy 21.0058 -87.0966) (xy 21.3868 -87.0966) (xy 21.3868 -87.6046) (xy 21.0058 -87.6046)
				)
			)
		)
	)
	(footprint ""
		(layer "F.Cu")
		(at 403.112986 -84.582 -90)
		(property "Reference" "U2P1"
			(at 2.1463 3.50901 90)
			(unlocked yes)
			(layer "F.SilkS")
			(effects
				(font
					(size 0.7874 0.5842)
					(thickness 0.1524)
				)
				(justify left)
			)
		)
		(property "Value" ""
			(at 0 0 270)
			(layer "F.Fab")
			(effects
				(font
					(size 1.27 1.27)
				)
			)
		)
		(duplicate_pad_numbers_are_jumpers no)
		(fp_circle
			(center -0.4699 -0.8382)
			(end -0.4699 -0.9652)
			(stroke
				(width 0.254)
				(type default)
			)
			(fill no)
			(layer "F.SilkS")
		)
		(fp_poly
			(pts
				(xy 0.21463 -0.450088) (xy 1.56337 -0.450088) (xy 1.56337 1.75006) (xy 0.21463 1.75006)
			)
			(stroke
				(width 0)
				(type default)
			)
			(fill no)
			(layer "F.CrtYd")
		)
		(fp_line
			(start 0.21463 1.75006)
			(end 0.21463 -0.450088)
			(stroke
				(width 0.1)
				(type default)
			)
			(layer "F.Fab")
		)
		(fp_line
			(start 1.56337 1.75006)
			(end 0.21463 1.75006)
			(stroke
				(width 0.1)
				(type default)
			)
			(layer "F.Fab")
		)
		(fp_line
			(start 0.21463 -0.450088)
			(end 1.56337 -0.450088)
			(stroke
				(width 0.1)
				(type default)
			)
			(layer "F.Fab")
		)
		(fp_line
			(start 1.56337 -0.450088)
			(end 1.56337 1.75006)
			(stroke
				(width 0.1)
				(type default)
			)
			(layer "F.Fab")
		)
		(fp_circle
			(center -0.4699 -0.8382)
			(end -0.4699 -0.9652)
			(stroke
				(width 0.254)
				(type default)
			)
			(fill no)
			(layer "F.Fab")
		)
		(pad "1" smd rect
			(at 0 0 270)
			(size 1.016 0.381)
			(layers "F.Cu" "F.Mask" "F.Paste")
			(net "Net_6470")
		)
		(pad "2" smd rect
			(at 0 0.649986 270)
			(size 1.016 0.381)
			(layers "F.Cu" "F.Mask" "F.Paste")
			(net "FM_M2_SSD_PEDET")
		)
		(pad "3" smd rect
			(at 0 1.299972 270)
			(size 1.016 0.381)
			(layers "F.Cu" "F.Mask" "F.Paste")
			(net "GND")
		)
		(pad "4" smd rect
			(at 1.778 1.299972 270)
			(size 1.016 0.381)
			(layers "F.Cu" "F.Mask" "F.Paste")
			(net "FM_M2_DET_LVC3")
		)
		(pad "5" smd rect
			(at 1.778 0 270)
			(size 1.016 0.381)
			(layers "F.Cu" "F.Mask" "F.Paste")
			(net "P3V3_STBY")
		)
	)
	(footprint ""
		(layer "F.Cu")
		(at 426.5295 -126.5047 -90)
		(property "Reference" "R8B11"
			(at 0 0 270)
			(layer "F.SilkS")
			(hide yes)
			(effects
				(font
					(size 1.27 1.27)
				)
			)
		)
		(property "Value" ""
			(at 0 0 270)
			(layer "F.Fab")
			(effects
				(font
					(size 1.27 1.27)
				)
			)
		)
		(duplicate_pad_numbers_are_jumpers no)
		(fp_poly
			(pts
				(xy -0.2794 -0.1016) (xy 0.2794 -0.1016) (xy 0.2794 0.9906) (xy -0.2794 0.9906)
			)
			(stroke
				(width 0)
				(type default)
			)
			(fill no)
			(layer "F.CrtYd")
		)
		(fp_line
			(start -0.2794 0.9906)
			(end 0.2794 0.9906)
			(stroke
				(width 0.1)
				(type default)
			)
			(layer "F.Fab")
		)
		(fp_line
			(start 0.2794 0.9906)
			(end 0.2794 -0.1016)
			(stroke
				(width 0.1)
				(type default)
			)
			(layer "F.Fab")
		)
		(fp_line
			(start -0.2794 -0.1016)
			(end -0.2794 0.9906)
			(stroke
				(width 0.1)
				(type default)
			)
			(layer "F.Fab")
		)
		(fp_line
			(start 0.2794 -0.1016)
			(end -0.2794 -0.1016)
			(stroke
				(width 0.1)
				(type default)
			)
			(layer "F.Fab")
		)
		(pad "1" smd rect
			(at 0 0 270)
			(size 0.508 0.508)
			(layers "F.Cu" "F.Mask" "F.Paste")
			(net "PVPP_ABC")
		)
		(pad "2" smd rect
			(at 0 0.889 270)
			(size 0.508 0.508)
			(layers "F.Cu" "F.Mask" "F.Paste")
			(net "SMB_HFI1_CPU0_LVC2_SCL")
		)
		(zone
			(layer "F.Cu")
			(hatch none 0.5)
			(connect_pads
				(clearance 0)
			)
			(min_thickness 0.25)
			(keepout
				(tracks not_allowed)
				(vias allowed)
				(pads allowed)
				(copperpour not_allowed)
				(footprints allowed)
			)
			(placement
				(enabled no)
				(sheetname "")
			)
			(fill
				(thermal_gap 0.5)
				(thermal_bridge_width 0.5)
				(island_removal_mode 0)
			)
			(polygon
				(pts
					(xy 425.8945 -126.7587) (xy 425.8945 -126.2507) (xy 426.2755 -126.2507) (xy 426.2755 -126.7587)
				)
			)
		)
		(zone
			(layer "F.Cu")
			(hatch none 0.5)
			(connect_pads
				(clearance 0)
			)
			(min_thickness 0.25)
			(keepout
				(tracks allowed)
				(vias not_allowed)
				(pads allowed)
				(copperpour not_allowed)
				(footprints allowed)
			)
			(placement
				(enabled no)
				(sheetname "")
			)
			(fill
				(thermal_gap 0.5)
				(thermal_bridge_width 0.5)
				(island_removal_mode 0)
			)
			(polygon
				(pts
					(xy 426.2755 -126.7587) (xy 426.2755 -126.2507) (xy 425.8945 -126.2507) (xy 425.8945 -126.7587)
				)
			)
		)
	)
)
